(kicad_pcb
	(version 20241229)
	(generator "pcbnew")
	(generator_version "9.0")
	(general
		(thickness 1.552)
		(legacy_teardrops no)
	)
	(paper "A4")
	(title_block
		(date "2023-07-25")
		(rev "1.1.4")
		(comment 9 "footprints 86-89 of 379")
	)
	(layers
		(0 "F.Cu" signal)
		(4 "In1.Cu" signal)
		(6 "In2.Cu" signal)
		(8 "In3.Cu" signal)
		(10 "In4.Cu" signal)
		(12 "In5.Cu" signal)
		(14 "In6.Cu" signal)
		(2 "B.Cu" signal)
		(9 "F.Adhes" user "F.Adhesive")
		(11 "B.Adhes" user "B.Adhesive")
		(13 "F.Paste" user)
		(15 "B.Paste" user)
		(5 "F.SilkS" user "F.Silkscreen")
		(7 "B.SilkS" user "B.Silkscreen")
		(1 "F.Mask" user)
		(3 "B.Mask" user)
		(17 "Dwgs.User" user "User.Drawings")
		(19 "Cmts.User" user "User.Comments")
		(21 "Eco1.User" user "User.Eco1")
		(23 "Eco2.User" user "User.Eco2")
		(25 "Edge.Cuts" user)
		(27 "Margin" user)
		(31 "F.CrtYd" user "F.Courtyard")
		(29 "B.CrtYd" user "B.Courtyard")
		(35 "F.Fab" user)
		(33 "B.Fab" user)
	)
	(footprint "antmicro-footprints:C_0603_1608Metric"
		(layer "F.Cu")
		(at 149.08 70.85 -90)
		(descr "Capacitor SMD 0603")
		(tags "capacitor 0603")
		(property "Reference" "C20"
			(at -1.46 -1.33 90)
			(layer "F.SilkS")
			(effects
				(font
					(size 0.65 0.65)
					(thickness 0.15)
				)
				(justify right bottom)
			)
		)
		(property "Value" "C_22u_0603"
			(at 0 1.6 90)
			(layer "F.Fab")
			(hide yes)
			(effects
				(font
					(size 0.7 0.7)
					(thickness 0.15)
				)
				(justify right bottom)
			)
		)
		(property "Datasheet" "https://www.murata.com/products/productdetail?partno=GRM188R60J226MEA0%23"
			(at 0 0 270)
			(layer "F.Fab")
			(hide yes)
			(effects
				(font
					(size 1.27 1.27)
					(thickness 0.15)
				)
			)
		)
		(property "Description" "SMD Multilayer Ceramic Capacitor, 22 µF, 6.3 V, 0603 [1608 Metric], ± 20%, X5R, GRM Series"
			(at 0 0 270)
			(layer "F.Fab")
			(hide yes)
			(effects
				(font
					(size 1.27 1.27)
					(thickness 0.15)
				)
			)
		)
		(property "Author" "Antmicro"
			(at 78.23 219.93 0)
			(layer "F.Fab")
			(hide yes)
			(effects
				(font
					(size 1 1)
					(thickness 0.15)
				)
			)
		)
		(property "Dielectric" ""
			(at 78.23 219.93 0)
			(layer "F.Fab")
			(hide yes)
			(effects
				(font
					(size 1 1)
					(thickness 0.15)
				)
			)
		)
		(property "License" "Apache-2.0"
			(at 78.23 219.93 0)
			(layer "F.Fab")
			(hide yes)
			(effects
				(font
					(size 1 1)
					(thickness 0.15)
				)
			)
		)
		(property "MPN" "GRM188R60J226MEA0D"
			(at 78.23 219.93 0)
			(layer "F.Fab")
			(hide yes)
			(effects
				(font
					(size 1 1)
					(thickness 0.15)
				)
			)
		)
		(property "Manufacturer" "Murata"
			(at 78.23 219.93 0)
			(layer "F.Fab")
			(hide yes)
			(effects
				(font
					(size 1 1)
					(thickness 0.15)
				)
			)
		)
		(property "Val" "22u"
			(at 78.23 219.93 0)
			(layer "F.Fab")
			(hide yes)
			(effects
				(font
					(size 1 1)
					(thickness 0.15)
				)
			)
		)
		(property "Voltage" ""
			(at 78.23 219.93 0)
			(layer "F.Fab")
			(hide yes)
			(effects
				(font
					(size 1 1)
					(thickness 0.15)
				)
			)
		)
		(sheetname "/Power Supply/")
		(sheetfile "supply.kicad_sch")
		(attr smd)
		(fp_line
			(start -0.15 0.4)
			(end 0.15 0.4)
			(stroke
				(width 0.15)
				(type solid)
			)
			(layer "F.SilkS")
		)
		(fp_line
			(start -0.15 -0.4)
			(end 0.15 -0.4)
			(stroke
				(width 0.15)
				(type solid)
			)
			(layer "F.SilkS")
		)
		(fp_rect
			(start -1.25 -0.65)
			(end 1.25 0.65)
			(stroke
				(width 0.05)
				(type solid)
			)
			(fill no)
			(layer "F.CrtYd")
		)
		(fp_rect
			(start -0.8 -0.4)
			(end 0.8 0.4)
			(stroke
				(width 0.15)
				(type solid)
			)
			(fill no)
			(layer "F.Fab")
		)
		(fp_text user "License: Apache-2.0"
			(at -1.682 5.895 270)
			(layer "F.Fab")
			(effects
				(font
					(size 0.7 0.7)
					(thickness 0.15)
				)
				(justify left bottom)
			)
		)
		(fp_text user "${REFERENCE}"
			(at -1.682 3.895 270)
			(layer "F.Fab")
			(effects
				(font
					(size 0.7 0.7)
					(thickness 0.15)
				)
				(justify left bottom)
			)
		)
		(fp_text user "Author: Antmicro"
			(at -1.682 4.894 270)
			(layer "F.Fab")
			(effects
				(font
					(size 0.7 0.7)
					(thickness 0.15)
				)
				(justify left bottom)
			)
		)
		(pad "1" smd roundrect
			(at -0.7 0 270)
			(size 0.8 1)
			(layers "F.Cu" "F.Mask" "F.Paste")
			(roundrect_rratio 0.2)
			(net 1 "GND")
			(pintype "passive")
		)
		(pad "2" smd roundrect
			(at 0.7 0 270)
			(size 0.8 1)
			(layers "F.Cu" "F.Mask" "F.Paste")
			(roundrect_rratio 0.2)
			(net 273 "/Power Supply/1V0_OUT")
			(pintype "passive")
		)
	)
	(footprint "antmicro-footprints:R_0402_1005Metric"
		(layer "F.Cu")
		(at 144.84 107.9 180)
		(descr "Resistor SMD 0402")
		(tags "resistor SMD 0402")
		(property "Reference" "R19"
			(at -0.99 -0.44 180)
			(layer "F.SilkS")
			(effects
				(font
					(size 0.65 0.65)
					(thickness 0.15)
				)
				(justify left bottom)
			)
		)
		(property "Value" "R_0R_0402"
			(at 0 1.4 180)
			(layer "F.Fab")
			(hide yes)
			(effects
				(font
					(size 0.7 0.7)
					(thickness 0.15)
				)
				(justify left bottom)
			)
		)
		(property "Datasheet" "https://industrial.panasonic.com/cdbs/www-data/pdf/RDA0000/AOA0000C301.pdf"
			(at 0 0 180)
			(layer "F.Fab")
			(hide yes)
			(effects
				(font
					(size 1.27 1.27)
					(thickness 0.15)
				)
			)
		)
		(property "Description" "SMD Chip Resistor, Jumper, 0 ohm, 100 mW, 0402 [1005 Metric], Thick Film, General Purpose"
			(at 0 0 180)
			(layer "F.Fab")
			(hide yes)
			(effects
				(font
					(size 1.27 1.27)
					(thickness 0.15)
				)
			)
		)
		(property "Author" "Antmicro"
			(at 289.68 215.8 0)
			(layer "F.Fab")
			(hide yes)
			(effects
				(font
					(size 1 1)
					(thickness 0.15)
				)
			)
		)
		(property "Current" "1A"
			(at 289.68 215.8 0)
			(layer "F.Fab")
			(hide yes)
			(effects
				(font
					(size 1 1)
					(thickness 0.15)
				)
			)
		)
		(property "License" "Apache-2.0"
			(at 289.68 215.8 0)
			(layer "F.Fab")
			(hide yes)
			(effects
				(font
					(size 1 1)
					(thickness 0.15)
				)
			)
		)
		(property "MPN" "ERJ2GE0R00X"
			(at 289.68 215.8 0)
			(layer "F.Fab")
			(hide yes)
			(effects
				(font
					(size 1 1)
					(thickness 0.15)
				)
			)
		)
		(property "Manufacturer" "Panasonic"
			(at 289.68 215.8 0)
			(layer "F.Fab")
			(hide yes)
			(effects
				(font
					(size 1 1)
					(thickness 0.15)
				)
			)
		)
		(property "Tolerance" "~"
			(at 289.68 215.8 0)
			(layer "F.Fab")
			(hide yes)
			(effects
				(font
					(size 1 1)
					(thickness 0.15)
				)
			)
		)
		(property "Val" "0R"
			(at 289.68 215.8 0)
			(layer "F.Fab")
			(hide yes)
			(effects
				(font
					(size 1 1)
					(thickness 0.15)
				)
			)
		)
		(sheetname "/Power Supply/")
		(sheetfile "supply.kicad_sch")
		(attr smd)
		(fp_rect
			(start -0.925 -0.47)
			(end 0.925 0.47)
			(stroke
				(width 0.05)
				(type default)
			)
			(fill no)
			(layer "F.CrtYd")
		)
		(fp_rect
			(start -0.5 -0.25)
			(end 0.5 0.25)
			(stroke
				(width 0.15)
				(type solid)
			)
			(fill no)
			(layer "F.Fab")
		)
		(fp_text user "License: Apache-2.0"
			(at -0.95 5.169 180)
			(layer "F.Fab")
			(effects
				(font
					(size 0.7 0.7)
					(thickness 0.15)
				)
				(justify left bottom)
			)
		)
		(fp_text user "Author: Antmicro"
			(at -0.95 4.169 180)
			(layer "F.Fab")
			(effects
				(font
					(size 0.7 0.7)
					(thickness 0.15)
				)
				(justify left bottom)
			)
		)
		(fp_text user "${REFERENCE}"
			(at -0.95 3.168 180)
			(layer "F.Fab")
			(effects
				(font
					(size 0.7 0.7)
					(thickness 0.15)
				)
				(justify left bottom)
			)
		)
		(pad "1" smd roundrect
			(at -0.48 0 180)
			(size 0.59 0.64)
			(layers "F.Cu" "F.Mask" "F.Paste")
			(roundrect_rratio 0.25)
			(net 2 "+3V3")
			(pintype "passive")
		)
		(pad "2" smd roundrect
			(at 0.48 0 180)
			(size 0.59 0.64)
			(layers "F.Cu" "F.Mask" "F.Paste")
			(roundrect_rratio 0.25)
			(net 264 "Net-(U8-V_{IN})")
			(pintype "passive")
		)
	)
	(footprint "antmicro-footprints:R_0402_1005Metric"
		(layer "F.Cu")
		(at 122.03 110.65 180)
		(descr "Resistor SMD 0402")
		(tags "resistor SMD 0402")
		(property "Reference" "R93"
			(at 0.95 -0.39 0)
			(layer "F.SilkS")
			(effects
				(font
					(size 0.65 0.65)
					(thickness 0.15)
				)
				(justify right bottom)
			)
		)
		(property "Value" "R_2k2_0402"
			(at 0 1.4 0)
			(layer "F.Fab")
			(hide yes)
			(effects
				(font
					(size 0.7 0.7)
					(thickness 0.15)
				)
				(justify right bottom)
			)
		)
		(property "Datasheet" "https://www.bourns.com/docs/product-datasheets/cr.pdf"
			(at 0 0 180)
			(layer "F.Fab")
			(hide yes)
			(effects
				(font
					(size 1.27 1.27)
					(thickness 0.15)
				)
			)
		)
		(property "Description" "SMD Chip Resistor, 2.2 kohm, ± 1%, 62.5 mW, 0402 [1005 Metric], Thick Film, General Purpose"
			(at 0 0 180)
			(layer "F.Fab")
			(hide yes)
			(effects
				(font
					(size 1.27 1.27)
					(thickness 0.15)
				)
			)
		)
		(property "Author" "Antmicro"
			(at 244.06 221.3 0)
			(layer "F.Fab")
			(hide yes)
			(effects
				(font
					(size 1 1)
					(thickness 0.15)
				)
			)
		)
		(property "License" "Apache-2.0"
			(at 244.06 221.3 0)
			(layer "F.Fab")
			(hide yes)
			(effects
				(font
					(size 1 1)
					(thickness 0.15)
				)
			)
		)
		(property "MPN" "CR0402-FX-2201GLF"
			(at 244.06 221.3 0)
			(layer "F.Fab")
			(hide yes)
			(effects
				(font
					(size 1 1)
					(thickness 0.15)
				)
			)
		)
		(property "Manufacturer" "Bourns"
			(at 244.06 221.3 0)
			(layer "F.Fab")
			(hide yes)
			(effects
				(font
					(size 1 1)
					(thickness 0.15)
				)
			)
		)
		(property "Tolerance" "1%"
			(at 244.06 221.3 0)
			(layer "F.Fab")
			(hide yes)
			(effects
				(font
					(size 1 1)
					(thickness 0.15)
				)
			)
		)
		(property "Val" "2k2"
			(at 244.06 221.3 0)
			(layer "F.Fab")
			(hide yes)
			(effects
				(font
					(size 1 1)
					(thickness 0.15)
				)
			)
		)
		(sheetname "/FPGA/")
		(sheetfile "fpga.kicad_sch")
		(attr smd)
		(fp_rect
			(start -0.925 -0.47)
			(end 0.925 0.47)
			(stroke
				(width 0.05)
				(type default)
			)
			(fill no)
			(layer "F.CrtYd")
		)
		(fp_rect
			(start -0.5 -0.25)
			(end 0.5 0.25)
			(stroke
				(width 0.15)
				(type solid)
			)
			(fill no)
			(layer "F.Fab")
		)
		(fp_text user "License: Apache-2.0"
			(at -0.95 5.169 180)
			(layer "F.Fab")
			(effects
				(font
					(size 0.7 0.7)
					(thickness 0.15)
				)
				(justify left bottom)
			)
		)
		(fp_text user "Author: Antmicro"
			(at -0.95 4.169 180)
			(layer "F.Fab")
			(effects
				(font
					(size 0.7 0.7)
					(thickness 0.15)
				)
				(justify left bottom)
			)
		)
		(fp_text user "${REFERENCE}"
			(at -0.95 3.168 180)
			(layer "F.Fab")
			(effects
				(font
					(size 0.7 0.7)
					(thickness 0.15)
				)
				(justify left bottom)
			)
		)
		(pad "1" smd roundrect
			(at -0.48 0 180)
			(size 0.59 0.64)
			(layers "F.Cu" "F.Mask" "F.Paste")
			(roundrect_rratio 0.25)
			(net 245 "Net-(D6-A)")
			(pintype "passive")
		)
		(pad "2" smd roundrect
			(at 0.48 0 180)
			(size 0.59 0.64)
			(layers "F.Cu" "F.Mask" "F.Paste")
			(roundrect_rratio 0.25)
			(net 2 "+3V3")
			(pintype "passive")
		)
	)
	(footprint "antmicro-footprints:UQFN-16-1.8x2.6mm_P0.4mm_Texas_RSV0016A"
		(layer "F.Cu")
		(at 110.205 95.79 180)
		(descr "https://www.ti.com/lit/ds/symlink/sn74avch4t245-ep.pdf?ts=1679484181203&ref_url=https%253A%252F%252Fwww.ti.com%252Fproduct%252FSN74AVCH4T245-EP%253Futm_source%253Dgoogle%2526utm_medium%253Dcpc%2526utm_campaign%253Dasc-int-null-prodfolderdynamic-cpc-pf-google-wwe_int%2526utm_content%253Dprodfolddynamic%2526ds_k%253DDYNAMIC%2BSEARCH%2BADS%2526DCM%253Dyes%2526gclid%253DCjwKCAjwzuqgBhAcEiwAdj5dRvR_WgyvqqhLxMx8zfbFv2a6tg33JIMv01Bn4M1kA4JzW1nDDW7OzhoCRbkQAvD_BwE%2526gclsrc%253Daw.ds")
		(property "Reference" "U21"
			(at 1.125 1.6 180)
			(layer "F.SilkS")
			(effects
				(font
					(size 0.7 0.7)
					(thickness 0.15)
				)
				(justify left bottom)
			)
		)
		(property "Value" "TMUX1574RSVR"
			(at -1.25 2.5 180)
			(layer "F.Fab")
			(effects
				(font
					(size 0.7 0.7)
					(thickness 0.15)
				)
				(justify left bottom)
			)
		)
		(property "Datasheet" "https://www.ti.com/lit/ds/symlink/tmux1574.pdf?ts=1672927977241&ref_url=https%253A%252F%252Fwww.ti.com%252Fproduct%252FTMUX1574%253FHQS%253DTI-null-null-octopart-df-pf-xrefTI-wwe"
			(at 0 0 180)
			(layer "F.Fab")
			(hide yes)
			(effects
				(font
					(size 1.27 1.27)
					(thickness 0.15)
				)
			)
		)
		(property "Description" "Analogue switch"
			(at 0 0 180)
			(layer "F.Fab")
			(hide yes)
			(effects
				(font
					(size 1.27 1.27)
					(thickness 0.15)
				)
			)
		)
		(property "Author" "Antmicro"
			(at 220.41 191.58 0)
			(layer "F.Fab")
			(hide yes)
			(effects
				(font
					(size 1 1)
					(thickness 0.15)
				)
			)
		)
		(property "License" "Apache-2.0"
			(at 220.41 191.58 0)
			(layer "F.Fab")
			(hide yes)
			(effects
				(font
					(size 1 1)
					(thickness 0.15)
				)
			)
		)
		(property "MPN" "TMUX1574RSVR"
			(at 220.41 191.58 0)
			(layer "F.Fab")
			(hide yes)
			(effects
				(font
					(size 1 1)
					(thickness 0.15)
				)
			)
		)
		(property "Manufacturer" "Texas Instruments"
			(at 220.41 191.58 0)
			(layer "F.Fab")
			(hide yes)
			(effects
				(font
					(size 1 1)
					(thickness 0.15)
				)
			)
		)
		(sheetname "/FPGA/")
		(sheetfile "fpga.kicad_sch")
		(attr smd)
		(fp_line
			(start 0.9 0.8)
			(end 0.899 1.3)
			(stroke
				(width 0.15)
				(type solid)
			)
			(layer "F.SilkS")
		)
		(fp_line
			(start 0.9 -1.3)
			(end 0.9 -0.8005)
			(stroke
				(width 0.15)
				(type solid)
			)
			(layer "F.SilkS")
		)
		(fp_line
			(start 0.8 1.3)
			(end 0.899 1.3)
			(stroke
				(width 0.15)
				(type solid)
			)
			(layer "F.SilkS")
		)
		(fp_line
			(start 0.8 -1.3)
			(end 0.9 -1.3)
			(stroke
				(width 0.15)
				(type solid)
			)
			(layer "F.SilkS")
		)
		(fp_line
			(start -0.8 1.2995)
			(end -0.9 1.2995)
			(stroke
				(width 0.15)
				(type solid)
			)
			(layer "F.SilkS")
		)
		(fp_line
			(start -0.8 -1.3)
			(end -0.9 -1.3)
			(stroke
				(width 0.15)
				(type solid)
			)
			(layer "F.SilkS")
		)
		(fp_line
			(start -0.9 1.2995)
			(end -0.9 0.8)
			(stroke
				(width 0.15)
				(type solid)
			)
			(layer "F.SilkS")
		)
		(fp_rect
			(start -1.25 -1.65)
			(end 1.25 1.65)
			(stroke
				(width 0.05)
				(type solid)
			)
			(fill no)
			(layer "F.CrtYd")
		)
		(fp_line
			(start 0.9 1.3)
			(end 0.9 -1.301)
			(stroke
				(width 0.15)
				(type solid)
			)
			(layer "F.Fab")
		)
		(fp_line
			(start 0.9 1.3)
			(end -0.902 1.3)
			(stroke
				(width 0.15)
				(type solid)
			)
			(layer "F.Fab")
		)
		(fp_line
			(start 0.9 -1.301)
			(end -0.902 -1.301)
			(stroke
				(width 0.15)
				(type solid)
			)
			(layer "F.Fab")
		)
		(fp_line
			(start -0.902 1.3)
			(end -0.902 -1.301)
			(stroke
				(width 0.15)
				(type solid)
			)
			(layer "F.Fab")
		)
		(fp_text user "."
			(at -1.45 -0.75 180)
			(layer "F.SilkS")
			(effects
				(font
					(size 0.7 0.7)
					(thickness 0.15)
				)
				(justify left bottom)
			)
		)
		(pad "1" smd roundrect
			(at -0.75 -0.6 180)
			(size 0.7 0.2)
			(layers "F.Cu" "F.Mask" "F.Paste")
			(roundrect_rratio 0.2272727273)
			(net 32 "/FPGA/MOSI_SOFT")
			(pinfunction "S1B")
			(pintype "bidirectional")
		)
		(pad "2" smd roundrect
			(at -0.802 -0.202 180)
			(size 0.6 0.2)
			(layers "F.Cu" "F.Mask" "F.Paste")
			(roundrect_rratio 0.2272727273)
			(net 300 "Net-(U18-SI{slash}IO0)")
			(pinfunction "D1")
			(pintype "bidirectional")
		)
		(pad "3" smd roundrect
			(at -0.802 0.2 180)
			(size 0.6 0.2)
			(layers "F.Cu" "F.Mask" "F.Paste")
			(roundrect_rratio 0.2272727273)
			(net 38 "/FPGA/SPI_DQ1_MISO")
			(pinfunction "S2A")
			(pintype "bidirectional")
		)
		(pad "4" smd roundrect
			(at -0.802 0.598 180)
			(size 0.6 0.2)
			(layers "F.Cu" "F.Mask" "F.Paste")
			(roundrect_rratio 0.2272727273)
			(net 31 "/FPGA/MISO_SOFT")
			(pinfunction "S2B")
			(pintype "bidirectional")
		)
		(pad "5" smd roundrect
			(at -0.6 1.199 270)
			(size 0.6 0.2)
			(layers "F.Cu" "F.Mask" "F.Paste")
			(roundrect_rratio 0.2272727273)
			(net 301 "Net-(U18-SO{slash}IO1)")
			(pinfunction "D2")
			(pintype "bidirectional")
		)
		(pad "6" smd roundrect
			(at -0.202 1.199 270)
			(size 0.6 0.2)
			(layers "F.Cu" "F.Mask" "F.Paste")
			(roundrect_rratio 0.2272727273)
			(net 1 "GND")
			(pinfunction "GND")
			(pintype "power_in")
		)
		(pad "7" smd roundrect
			(at 0.2 1.199 270)
			(size 0.6 0.2)
			(layers "F.Cu" "F.Mask" "F.Paste")
			(roundrect_rratio 0.2272727273)
			(net 303 "Net-(U18-SCLK)")
			(pinfunction "D3")
			(pintype "bidirectional")
		)
		(pad "8" smd roundrect
			(at 0.598 1.199 270)
			(size 0.6 0.2)
			(layers "F.Cu" "F.Mask" "F.Paste")
			(roundrect_rratio 0.2272727273)
			(net 33 "/FPGA/SPI_CLK_SOFT")
			(pinfunction "S3B")
			(pintype "bidirectional")
		)
		(pad "9" smd roundrect
			(at 0.8 0.598 180)
			(size 0.6 0.2)
			(layers "F.Cu" "F.Mask" "F.Paste")
			(roundrect_rratio 0.2272727273)
			(net 39 "/FPGA/SPI_CLK")
			(pinfunction "S3A")
			(pintype "bidirectional")
		)
		(pad "10" smd roundrect
			(at 0.8 0.2 180)
			(size 0.6 0.2)
			(layers "F.Cu" "F.Mask" "F.Paste")
			(roundrect_rratio 0.2272727273)
			(net 324 "Net-(U21-D4)")
			(pinfunction "D4")
			(pintype "bidirectional")
		)
		(pad "11" smd roundrect
			(at 0.8 -0.202 180)
			(size 0.6 0.2)
			(layers "F.Cu" "F.Mask" "F.Paste")
			(roundrect_rratio 0.2272727273)
			(net 29 "/FPGA/~{FLASH_CS_SOFT}")
			(pinfunction "S4B")
			(pintype "bidirectional")
		)
		(pad "12" smd roundrect
			(at 0.8 -0.6 180)
			(size 0.6 0.2)
			(layers "F.Cu" "F.Mask" "F.Paste")
			(roundrect_rratio 0.2272727273)
			(net 41 "/FPGA/~{FLASH_CS}")
			(pinfunction "S4A")
			(pintype "bidirectional")
		)
		(pad "13" smd roundrect
			(at 0.598 -1.2 270)
			(size 0.6 0.2)
			(layers "F.Cu" "F.Mask" "F.Paste")
			(roundrect_rratio 0.2272727273)
			(net 1 "GND")
			(pinfunction "~{EN}")
			(pintype "input")
		)
		(pad "14" smd roundrect
			(at 0.2 -1.2 270)
			(size 0.6 0.2)
			(layers "F.Cu" "F.Mask" "F.Paste")
			(roundrect_rratio 0.2272727273)
			(net 2 "+3V3")
			(pinfunction "VDD")
			(pintype "power_in")
		)
		(pad "15" smd roundrect
			(at -0.202 -1.2 270)
			(size 0.6 0.2)
			(layers "F.Cu" "F.Mask" "F.Paste")
			(roundrect_rratio 0.2272727273)
			(net 376 "/FPGA/SEL")
			(pinfunction "SEL")
			(pintype "input")
		)
		(pad "16" smd roundrect
			(at -0.6 -1.2 270)
			(size 0.6 0.2)
			(layers "F.Cu" "F.Mask" "F.Paste")
			(roundrect_rratio 0.2272727273)
			(net 37 "/FPGA/SPI_DQ0_MOSI")
			(pinfunction "S1A")
			(pintype "bidirectional")
		)
	)
)
